# T6G (Grand Teton) — schematic netlist excerpt (pin names and nets, part order shuffled) for the footprints in the layout excerpt that follows; sources: Cadence DE-HDL packaged netlist, KiCad conversion of 04192023_DAF0TMB3IC0_F0TG_MB_C_brd_V02_OCP.brd

PC2219  Q_CAP  10UF 16V 10% X6S  pkg C0805  page 146 : A = P12V_E1S_0 ; B = GND
R893  Q_RES  0 5% EMPTY  pkg 0402LF  page 356 : A = P1V8_CPU1_RT3_1A_1D ; B = P1V8_CPU1_RT3_1A
R3727  Q_RES  2.2K 5% CHIP  pkg 0402LF  page 252 : A = P3V3_AUX ; B = SMB_LM75_1_3V3AUX_SCL

(kicad_pcb
	(version 20260206)
	(generator "pcbnew")
	(generator_version "10.0")
	(general
		(thickness 1.6)
		(legacy_teardrops no)
	)
	(paper "A4")
	(title_block
		(title "04192023_DAF0TMB3IC0_F0TG_MB_C_brd_V02_OCP.brd")
		(comment 1 "Grand Teton / footprints 1639-1641 of 8354")
	)
	(layers
		(0 "F.Cu" signal "TOP")
		(4 "In1.Cu" signal "GND")
		(6 "In2.Cu" signal "IN1")
		(8 "In3.Cu" signal "GND1")
		(10 "In4.Cu" signal "IN2")
		(12 "In5.Cu" signal "GND2")
		(14 "In6.Cu" signal "IN3")
		(16 "In7.Cu" signal "GND3")
		(18 "In8.Cu" signal "VCC")
		(20 "In9.Cu" signal "VCC1")
		(22 "In10.Cu" signal "GND4")
		(24 "In11.Cu" signal "IN4")
		(26 "In12.Cu" signal "GND5")
		(28 "In13.Cu" signal "IN5")
		(30 "In14.Cu" signal "GND6")
		(32 "In15.Cu" signal "IN6")
		(34 "In16.Cu" signal "GND7")
		(2 "B.Cu" signal "BOTTOM")
		(9 "F.Adhes" user "F.Adhesive")
		(11 "B.Adhes" user "B.Adhesive")
		(13 "F.Paste" user "Package Geometry/Pastemask Top")
		(15 "B.Paste" user "Package Geometry/Pastemask Bottom")
		(5 "F.SilkS" user "Ref Des/Silkscreen Top")
		(7 "B.SilkS" user "Ref Des/Silkscreen Bottom")
		(1 "F.Mask" user "Board Geometry/Soldermask Top")
		(3 "B.Mask" user "Board Geometry/Soldermask Bottom")
		(17 "Dwgs.User" user "User.Drawings")
		(19 "Cmts.User" user "User.Comments")
		(21 "Eco1.User" user "User.Eco1")
		(23 "Eco2.User" user "User.Eco2")
		(25 "Edge.Cuts" user "Board Geometry/Outline")
		(27 "Margin" user)
		(31 "F.CrtYd" user "Package Geometry/Place Bound Top")
		(29 "B.CrtYd" user "Package Geometry/Place Bound Bottom")
		(35 "F.Fab" user "Ref Des/Assembly Top")
		(33 "B.Fab" user "Ref Des/Assembly Bottom")
	)
	(footprint ""
		(layer "F.Cu")
		(at 136.962388 -384.10388 180)
		(property "Reference" "R893"
			(at 0 0 180)
			(layer "F.SilkS")
			(hide yes)
			(effects
				(font
					(size 1.27 1.27)
				)
			)
		)
		(property "Value" ""
			(at 0 0 180)
			(layer "F.Fab")
			(effects
				(font
					(size 1.27 1.27)
				)
			)
		)
		(duplicate_pad_numbers_are_jumpers no)
		(fp_line
			(start 0.7874 0.4064)
			(end -0.7874 0.4064)
			(stroke
				(width 0.1524)
				(type default)
			)
			(layer "F.SilkS")
		)
		(fp_line
			(start 0.7874 -0.4064)
			(end 0.7874 0.4064)
			(stroke
				(width 0.1524)
				(type default)
			)
			(layer "F.SilkS")
		)
		(fp_line
			(start -0.7874 0.4064)
			(end -0.7874 -0.4064)
			(stroke
				(width 0.1524)
				(type default)
			)
			(layer "F.SilkS")
		)
		(fp_line
			(start -0.7874 -0.4064)
			(end 0.7874 -0.4064)
			(stroke
				(width 0.1524)
				(type default)
			)
			(layer "F.SilkS")
		)
		(fp_line
			(start 0.67945 0.3048)
			(end 0.120396 0.3048)
			(stroke
				(width 0.1)
				(type default)
			)
			(layer "F.Fab")
		)
		(fp_line
			(start 0.67945 -0.3048)
			(end 0.67945 0.3048)
			(stroke
				(width 0.1)
				(type default)
			)
			(layer "F.Fab")
		)
		(fp_line
			(start 0.12065 -0.2794)
			(end 0.12065 -0.3048)
			(stroke
				(width 0.1)
				(type default)
			)
			(layer "F.Fab")
		)
		(fp_line
			(start 0.12065 -0.3048)
			(end 0.67945 -0.3048)
			(stroke
				(width 0.1)
				(type default)
			)
			(layer "F.Fab")
		)
		(fp_line
			(start 0.120396 0.3048)
			(end 0.120396 0.2794)
			(stroke
				(width 0.1)
				(type default)
			)
			(layer "F.Fab")
		)
		(fp_line
			(start 0.120396 0.2794)
			(end -0.12065 0.2794)
			(stroke
				(width 0.1)
				(type default)
			)
			(layer "F.Fab")
		)
		(fp_line
			(start -0.12065 0.3048)
			(end -0.67945 0.3048)
			(stroke
				(width 0.1)
				(type default)
			)
			(layer "F.Fab")
		)
		(fp_line
			(start -0.12065 0.2794)
			(end -0.12065 0.3048)
			(stroke
				(width 0.1)
				(type default)
			)
			(layer "F.Fab")
		)
		(fp_line
			(start -0.12065 -0.2794)
			(end 0.12065 -0.2794)
			(stroke
				(width 0.1)
				(type default)
			)
			(layer "F.Fab")
		)
		(fp_line
			(start -0.12065 -0.305054)
			(end -0.12065 -0.2794)
			(stroke
				(width 0.1)
				(type default)
			)
			(layer "F.Fab")
		)
		(fp_line
			(start -0.67945 0.3048)
			(end -0.67945 -0.305054)
			(stroke
				(width 0.1)
				(type default)
			)
			(layer "F.Fab")
		)
		(fp_line
			(start -0.67945 -0.305054)
			(end -0.12065 -0.305054)
			(stroke
				(width 0.1)
				(type default)
			)
			(layer "F.Fab")
		)
		(pad "1" smd rect
			(at -0.40005 0)
			(size 0.4572 0.508)
			(layers "F.Cu" "F.Mask" "F.Paste")
			(net "P1V8_CPU1_RT3_1A_1D")
		)
		(pad "2" smd rect
			(at 0.40005 0)
			(size 0.4572 0.508)
			(layers "F.Cu" "F.Mask" "F.Paste")
			(net "P1V8_CPU1_RT3_1A")
		)
	)
	(footprint ""
		(layer "F.Cu")
		(at 254.592836 -116.12245)
		(property "Reference" "R3727"
			(at 0 0 0)
			(layer "F.SilkS")
			(hide yes)
			(effects
				(font
					(size 1.27 1.27)
				)
			)
		)
		(property "Value" ""
			(at 0 0 0)
			(layer "F.Fab")
			(effects
				(font
					(size 1.27 1.27)
				)
			)
		)
		(duplicate_pad_numbers_are_jumpers no)
		(fp_line
			(start -0.7874 -0.4064)
			(end 0.7874 -0.4064)
			(stroke
				(width 0.1524)
				(type default)
			)
			(layer "F.SilkS")
		)
		(fp_line
			(start -0.7874 0.4064)
			(end -0.7874 -0.4064)
			(stroke
				(width 0.1524)
				(type default)
			)
			(layer "F.SilkS")
		)
		(fp_line
			(start 0.7874 -0.4064)
			(end 0.7874 0.4064)
			(stroke
				(width 0.1524)
				(type default)
			)
			(layer "F.SilkS")
		)
		(fp_line
			(start 0.7874 0.4064)
			(end -0.7874 0.4064)
			(stroke
				(width 0.1524)
				(type default)
			)
			(layer "F.SilkS")
		)
		(fp_line
			(start -0.67945 -0.305054)
			(end -0.12065 -0.305054)
			(stroke
				(width 0.1)
				(type default)
			)
			(layer "F.Fab")
		)
		(fp_line
			(start -0.67945 0.3048)
			(end -0.67945 -0.305054)
			(stroke
				(width 0.1)
				(type default)
			)
			(layer "F.Fab")
		)
		(fp_line
			(start -0.12065 -0.305054)
			(end -0.12065 -0.2794)
			(stroke
				(width 0.1)
				(type default)
			)
			(layer "F.Fab")
		)
		(fp_line
			(start -0.12065 -0.2794)
			(end 0.12065 -0.2794)
			(stroke
				(width 0.1)
				(type default)
			)
			(layer "F.Fab")
		)
		(fp_line
			(start -0.12065 0.2794)
			(end -0.12065 0.3048)
			(stroke
				(width 0.1)
				(type default)
			)
			(layer "F.Fab")
		)
		(fp_line
			(start -0.12065 0.3048)
			(end -0.67945 0.3048)
			(stroke
				(width 0.1)
				(type default)
			)
			(layer "F.Fab")
		)
		(fp_line
			(start 0.120396 0.2794)
			(end -0.12065 0.2794)
			(stroke
				(width 0.1)
				(type default)
			)
			(layer "F.Fab")
		)
		(fp_line
			(start 0.120396 0.3048)
			(end 0.120396 0.2794)
			(stroke
				(width 0.1)
				(type default)
			)
			(layer "F.Fab")
		)
		(fp_line
			(start 0.12065 -0.3048)
			(end 0.67945 -0.3048)
			(stroke
				(width 0.1)
				(type default)
			)
			(layer "F.Fab")
		)
		(fp_line
			(start 0.12065 -0.2794)
			(end 0.12065 -0.3048)
			(stroke
				(width 0.1)
				(type default)
			)
			(layer "F.Fab")
		)
		(fp_line
			(start 0.67945 -0.3048)
			(end 0.67945 0.3048)
			(stroke
				(width 0.1)
				(type default)
			)
			(layer "F.Fab")
		)
		(fp_line
			(start 0.67945 0.3048)
			(end 0.120396 0.3048)
			(stroke
				(width 0.1)
				(type default)
			)
			(layer "F.Fab")
		)
		(pad "1" smd circle
			(at -0.40005 0)
			(size 0 0)
			(layers "F.Cu" "F.Mask" "F.Paste")
			(net "P3V3_AUX")
		)
		(pad "2" smd circle
			(at 0.40005 0)
			(size 0 0)
			(layers "F.Cu" "F.Mask" "F.Paste")
			(net "SMB_LM75_1_3V3AUX_SCL")
		)
	)
	(footprint ""
		(layer "F.Cu")
		(at 246.22506 -53.997606 90)
		(property "Reference" "PC2219"
			(at 0 0 90)
			(layer "F.SilkS")
			(hide yes)
			(effects
				(font
					(size 1.27 1.27)
				)
			)
		)
		(property "Value" ""
			(at 0 0 90)
			(layer "F.Fab")
			(effects
				(font
					(size 1.27 1.27)
				)
			)
		)
		(duplicate_pad_numbers_are_jumpers no)
		(fp_line
			(start 1.524 -0.762)
			(end 1.524 0.762)
			(stroke
				(width 0.1524)
				(type default)
			)
			(layer "F.SilkS")
		)
		(fp_line
			(start -1.524 -0.762)
			(end 1.524 -0.762)
			(stroke
				(width 0.1524)
				(type default)
			)
			(layer "F.SilkS")
		)
		(fp_line
			(start 1.524 0.762)
			(end -1.524 0.762)
			(stroke
				(width 0.1524)
				(type default)
			)
			(layer "F.SilkS")
		)
		(fp_line
			(start -1.524 0.762)
			(end -1.524 -0.762)
			(stroke
				(width 0.1524)
				(type default)
			)
			(layer "F.SilkS")
		)
		(fp_line
			(start 1.1049 -0.724916)
			(end -1.1049 -0.724916)
			(stroke
				(width 0.1)
				(type default)
			)
			(layer "F.Fab")
		)
		(fp_line
			(start -1.1049 -0.724916)
			(end -1.1049 0.724916)
			(stroke
				(width 0.1)
				(type default)
			)
			(layer "F.Fab")
		)
		(fp_line
			(start 1.1049 0.724916)
			(end 1.1049 -0.724916)
			(stroke
				(width 0.1)
				(type default)
			)
			(layer "F.Fab")
		)
		(fp_line
			(start -1.1049 0.724916)
			(end 1.1049 0.724916)
			(stroke
				(width 0.1)
				(type default)
			)
			(layer "F.Fab")
		)
		(pad "1" smd rect
			(at -0.889 0 270)
			(size 1.016 1.27)
			(layers "F.Cu" "F.Mask" "F.Paste")
			(net "P12V_E1S_0")
		)
		(pad "2" smd rect
			(at 0.889 0 270)
			(size 1.016 1.27)
			(layers "F.Cu" "F.Mask" "F.Paste")
			(net "GND")
		)
	)
)
